(kicad_pcb
	(version 20260206)
	(generator "pcbnew")
	(generator_version "10.0")
	(general
		(thickness 1.6)
		(legacy_teardrops no)
	)
	(paper "A4")
	(title_block
		(title "Wiwynn_Tioga_Pass_MB.brd")
		(comment 1 "Tioga Pass / footprints 4175-4182 of 4770")
	)
	(layers
		(0 "F.Cu" signal "TOP")
		(4 "In1.Cu" signal "L2GND")
		(6 "In2.Cu" signal "L3")
		(8 "In3.Cu" signal "L4GND")
		(10 "In4.Cu" signal "L5")
		(12 "In5.Cu" signal "L6GND")
		(14 "In6.Cu" signal "L7VCC")
		(16 "In7.Cu" signal "L8VCC")
		(18 "In8.Cu" signal "L9GND")
		(20 "In9.Cu" signal "L10")
		(22 "In10.Cu" signal "L11GND")
		(24 "In11.Cu" signal "L12")
		(26 "In12.Cu" signal "L13GND")
		(2 "B.Cu" signal "BOTTOM")
		(9 "F.Adhes" user "F.Adhesive")
		(11 "B.Adhes" user "B.Adhesive")
		(13 "F.Paste" user "Package Geometry/Pastemask Top")
		(15 "B.Paste" user "Package Geometry/Pastemask Bottom")
		(5 "F.SilkS" user "Ref Des/Silkscreen Top")
		(7 "B.SilkS" user "Ref Des/Silkscreen Bottom")
		(1 "F.Mask" user "Board Geometry/Soldermask Top")
		(3 "B.Mask" user "Board Geometry/Soldermask Bottom")
		(17 "Dwgs.User" user "User.Drawings")
		(19 "Cmts.User" user "User.Comments")
		(21 "Eco1.User" user "User.Eco1")
		(23 "Eco2.User" user "User.Eco2")
		(25 "Edge.Cuts" user "Board Geometry/Outline")
		(27 "Margin" user)
		(31 "F.CrtYd" user "Package Geometry/Place Bound Top")
		(29 "B.CrtYd" user "Package Geometry/Place Bound Bottom")
		(35 "F.Fab" user "Ref Des/Assembly Top")
		(33 "B.Fab" user "Ref Des/Assembly Bottom")
	)
	(footprint ""
		(layer "B.Cu")
		(at 278.703024 -77.810614)
		(property "Reference" "C4P5"
			(at 0 0 0)
			(layer "B.SilkS")
			(hide yes)
			(effects
				(font
					(size 1.27 1.27)
				)
				(justify mirror)
			)
		)
		(property "Value" ""
			(at 0 0 0)
			(layer "B.Fab")
			(effects
				(font
					(size 1.27 1.27)
				)
				(justify mirror)
			)
		)
		(duplicate_pad_numbers_are_jumpers no)
		(fp_poly
			(pts
				(xy 0.7239 -0.2159) (xy -0.7239 -0.2159) (xy -0.7239 1.9939) (xy 0.7239 1.9939)
			)
			(stroke
				(width 0)
				(type default)
			)
			(fill no)
			(layer "B.CrtYd")
		)
		(fp_line
			(start -0.7239 -0.2159)
			(end 0.7239 -0.2159)
			(stroke
				(width 0.1)
				(type default)
			)
			(layer "B.Fab")
		)
		(fp_line
			(start -0.7239 1.9939)
			(end -0.7239 -0.2159)
			(stroke
				(width 0.1)
				(type default)
			)
			(layer "B.Fab")
		)
		(fp_line
			(start 0.7239 -0.2159)
			(end 0.7239 1.9939)
			(stroke
				(width 0.1)
				(type default)
			)
			(layer "B.Fab")
		)
		(fp_line
			(start 0.7239 1.9939)
			(end -0.7239 1.9939)
			(stroke
				(width 0.1)
				(type default)
			)
			(layer "B.Fab")
		)
		(pad "1" smd rect
			(at 0 0 180)
			(size 1.27 1.016)
			(layers "B.Cu" "B.Mask" "B.Paste")
			(net "PVCCMCP_CPU0")
		)
		(pad "2" smd rect
			(at 0 1.778 180)
			(size 1.27 1.016)
			(layers "B.Cu" "B.Mask" "B.Paste")
			(net "GND")
		)
		(zone
			(layer "B.Cu")
			(hatch none 0.5)
			(connect_pads
				(clearance 0)
			)
			(min_thickness 0.25)
			(keepout
				(tracks not_allowed)
				(vias allowed)
				(pads allowed)
				(copperpour not_allowed)
				(footprints allowed)
			)
			(placement
				(enabled no)
				(sheetname "")
			)
			(fill
				(thermal_gap 0.5)
				(thermal_bridge_width 0.5)
				(island_removal_mode 0)
			)
			(polygon
				(pts
					(xy 279.338024 -77.302614) (xy 278.068024 -77.302614) (xy 278.068024 -76.540614) (xy 279.338024 -76.540614)
				)
			)
		)
	)
	(footprint ""
		(layer "B.Cu")
		(at 169.770552 -22.654006 -90)
		(property "Reference" "R6T4"
			(at 0 0 90)
			(layer "B.SilkS")
			(hide yes)
			(effects
				(font
					(size 1.27 1.27)
				)
				(justify mirror)
			)
		)
		(property "Value" ""
			(at 0 0 90)
			(layer "B.Fab")
			(effects
				(font
					(size 1.27 1.27)
				)
				(justify mirror)
			)
		)
		(duplicate_pad_numbers_are_jumpers no)
		(fp_poly
			(pts
				(xy 0.2794 -0.1016) (xy -0.2794 -0.1016) (xy -0.2794 0.9906) (xy 0.2794 0.9906)
			)
			(stroke
				(width 0)
				(type default)
			)
			(fill no)
			(layer "B.CrtYd")
		)
		(fp_line
			(start -0.2794 0.9906)
			(end -0.2794 -0.1016)
			(stroke
				(width 0.1)
				(type default)
			)
			(layer "B.Fab")
		)
		(fp_line
			(start 0.2794 0.9906)
			(end -0.2794 0.9906)
			(stroke
				(width 0.1)
				(type default)
			)
			(layer "B.Fab")
		)
		(fp_line
			(start -0.2794 -0.1016)
			(end 0.2794 -0.1016)
			(stroke
				(width 0.1)
				(type default)
			)
			(layer "B.Fab")
		)
		(fp_line
			(start 0.2794 -0.1016)
			(end 0.2794 0.9906)
			(stroke
				(width 0.1)
				(type default)
			)
			(layer "B.Fab")
		)
		(pad "1" smd rect
			(at 0 0 90)
			(size 0.508 0.508)
			(layers "B.Cu" "B.Mask" "B.Paste")
			(net "SMB_DDR_GHJ_SDA_G_R")
		)
		(pad "2" smd rect
			(at 0 0.889 90)
			(size 0.508 0.508)
			(layers "B.Cu" "B.Mask" "B.Paste")
			(net "SMB_DDR_GHJ_SDA_G")
		)
		(zone
			(layer "B.Cu")
			(hatch none 0.5)
			(connect_pads
				(clearance 0)
			)
			(min_thickness 0.25)
			(keepout
				(tracks not_allowed)
				(vias allowed)
				(pads allowed)
				(copperpour not_allowed)
				(footprints allowed)
			)
			(placement
				(enabled no)
				(sheetname "")
			)
			(fill
				(thermal_gap 0.5)
				(thermal_bridge_width 0.5)
				(island_removal_mode 0)
			)
			(polygon
				(pts
					(xy 169.135552 -22.400006) (xy 169.135552 -22.908006) (xy 169.516552 -22.908006) (xy 169.516552 -22.400006)
				)
			)
		)
		(zone
			(layer "B.Cu")
			(hatch none 0.5)
			(connect_pads
				(clearance 0)
			)
			(min_thickness 0.25)
			(keepout
				(tracks allowed)
				(vias not_allowed)
				(pads allowed)
				(copperpour not_allowed)
				(footprints allowed)
			)
			(placement
				(enabled no)
				(sheetname "")
			)
			(fill
				(thermal_gap 0.5)
				(thermal_bridge_width 0.5)
				(island_removal_mode 0)
			)
			(polygon
				(pts
					(xy 169.516552 -22.400006) (xy 169.516552 -22.908006) (xy 169.135552 -22.908006) (xy 169.135552 -22.400006)
				)
			)
		)
	)
	(footprint ""
		(layer "B.Cu")
		(at 111.000032 -3.3528 90)
		(property "Reference" "C5G92"
			(at -1.14681 0.76708 180)
			(unlocked yes)
			(layer "B.SilkS")
			(effects
				(font
					(size 0.7874 0.5842)
					(thickness 0.1524)
				)
				(justify mirror)
			)
		)
		(property "Value" ""
			(at 0 0 90)
			(layer "B.Fab")
			(effects
				(font
					(size 1.27 1.27)
				)
				(justify mirror)
			)
		)
		(duplicate_pad_numbers_are_jumpers no)
		(fp_rect
			(start -0.4953 -0.2032)
			(end 0.4953 1.6002)
			(stroke
				(width 0)
				(type default)
			)
			(fill no)
			(layer "B.CrtYd")
		)
		(fp_line
			(start 0.4953 -0.2032)
			(end -0.4953 -0.2032)
			(stroke
				(width 0.1)
				(type default)
			)
			(layer "B.Fab")
		)
		(fp_line
			(start -0.4953 -0.2032)
			(end -0.4953 1.6002)
			(stroke
				(width 0.1)
				(type default)
			)
			(layer "B.Fab")
		)
		(fp_line
			(start 0.4953 1.6002)
			(end 0.4953 -0.2032)
			(stroke
				(width 0.1)
				(type default)
			)
			(layer "B.Fab")
		)
		(fp_line
			(start -0.4953 1.6002)
			(end 0.4953 1.6002)
			(stroke
				(width 0.1)
				(type default)
			)
			(layer "B.Fab")
		)
		(pad "1" smd rect
			(at 0 0 270)
			(size 0.762 0.889)
			(layers "B.Cu" "B.Mask" "B.Paste")
			(net "PVDDQ_GHJ")
		)
		(pad "2" smd rect
			(at 0 1.397 270)
			(size 0.762 0.889)
			(layers "B.Cu" "B.Mask" "B.Paste")
			(net "GND")
		)
		(zone
			(layer "B.Cu")
			(hatch none 0.5)
			(connect_pads
				(clearance 0)
			)
			(min_thickness 0.25)
			(keepout
				(tracks not_allowed)
				(vias allowed)
				(pads allowed)
				(copperpour not_allowed)
				(footprints allowed)
			)
			(placement
				(enabled no)
				(sheetname "")
			)
			(fill
				(thermal_gap 0.5)
				(thermal_bridge_width 0.5)
				(island_removal_mode 0)
			)
			(polygon
				(pts
					(xy 111.444532 -2.9718) (xy 111.952532 -2.9718) (xy 111.952532 -3.7338) (xy 111.444532 -3.7338)
				)
			)
		)
	)
	(footprint ""
		(layer "B.Cu")
		(at 441.119006 -43.54195 180)
		(property "Reference" "R25W50"
			(at 0 0 0)
			(layer "B.SilkS")
			(hide yes)
			(effects
				(font
					(size 1.27 1.27)
				)
				(justify mirror)
			)
		)
		(property "Value" "*"
			(at -0.064008 -4.108196 180)
			(unlocked yes)
			(layer "B.Fab")
			(hide yes)
			(effects
				(font
					(size 1.27 1.016)
					(thickness 0.1524)
				)
				(justify mirror)
			)
		)
		(property "Device Type" "120R2F-GP_RCL_GP-120R2F-GP,64.A"
			(at -0.064008 -5.632196 180)
			(unlocked yes)
			(layer "B.Fab")
			(hide yes)
			(effects
				(font
					(size 1.27 1.016)
					(thickness 0.1524)
				)
				(justify mirror)
			)
		)
		(duplicate_pad_numbers_are_jumpers no)
		(fp_line
			(start 0.508 -0.9398)
			(end 0.508 0.9398)
			(stroke
				(width 0.1524)
				(type default)
			)
			(layer "B.SilkS")
		)
		(fp_line
			(start -0.508 -0.9398)
			(end 0.508 -0.9398)
			(stroke
				(width 0.1524)
				(type default)
			)
			(layer "B.SilkS")
		)
		(fp_rect
			(start 0.508 0.9398)
			(end -0.508 -0.9398)
			(stroke
				(width 0)
				(type default)
			)
			(fill no)
			(layer "B.CrtYd")
		)
		(fp_rect
			(start 0.508 0.9398)
			(end -0.508 -0.9398)
			(stroke
				(width 0)
				(type default)
			)
			(fill no)
			(layer "B.Fab")
		)
		(pad "1" smd custom
			(at 0 -0.4445)
			(size 0.1397 0.1397)
			(layers "B.Cu" "B.Mask" "B.Paste")
			(net "BMC_M_A12")
			(options
				(clearance outline)
				(anchor circle)
			)
			(primitives
				(gr_poly
					(pts
						(arc
							(start -0.1778 0.2794)
							(mid -0.249642 0.249642)
							(end -0.2794 0.1778)
						)
						(arc
							(start -0.2794 -0.1778)
							(mid -0.249642 -0.249642)
							(end -0.1778 -0.2794)
						)
						(arc
							(start 0.1778 -0.2794)
							(mid 0.249642 -0.249642)
							(end 0.2794 -0.1778)
						)
						(arc
							(start 0.2794 0.1778)
							(mid 0.249642 0.249642)
							(end 0.1778 0.2794)
						)
					)
					(width 0)
					(fill yes)
				)
			)
		)
		(pad "2" smd custom
			(at 0 0.4445)
			(size 0.1397 0.1397)
			(layers "B.Cu" "B.Mask" "B.Paste")
			(net "P1V2_AUX_BMC")
			(options
				(clearance outline)
				(anchor circle)
			)
			(primitives
				(gr_poly
					(pts
						(arc
							(start -0.1778 0.2794)
							(mid -0.249642 0.249642)
							(end -0.2794 0.1778)
						)
						(arc
							(start -0.2794 -0.1778)
							(mid -0.249642 -0.249642)
							(end -0.1778 -0.2794)
						)
						(arc
							(start 0.1778 -0.2794)
							(mid 0.249642 -0.249642)
							(end 0.2794 -0.1778)
						)
						(arc
							(start 0.2794 0.1778)
							(mid 0.249642 0.249642)
							(end 0.1778 0.2794)
						)
					)
					(width 0)
					(fill yes)
				)
			)
		)
	)
	(footprint ""
		(layer "B.Cu")
		(at 407.9113 -8.763 90)
		(property "Reference" "R8D40"
			(at 0 0 90)
			(layer "B.SilkS")
			(hide yes)
			(effects
				(font
					(size 1.27 1.27)
				)
				(justify mirror)
			)
		)
		(property "Value" ""
			(at 0 0 90)
			(layer "B.Fab")
			(effects
				(font
					(size 1.27 1.27)
				)
				(justify mirror)
			)
		)
		(duplicate_pad_numbers_are_jumpers no)
		(fp_poly
			(pts
				(xy 0.2794 -0.1016) (xy -0.2794 -0.1016) (xy -0.2794 0.9906) (xy 0.2794 0.9906)
			)
			(stroke
				(width 0)
				(type default)
			)
			(fill no)
			(layer "B.CrtYd")
		)
		(fp_line
			(start 0.2794 -0.1016)
			(end 0.2794 0.9906)
			(stroke
				(width 0.1)
				(type default)
			)
			(layer "B.Fab")
		)
		(fp_line
			(start -0.2794 -0.1016)
			(end 0.2794 -0.1016)
			(stroke
				(width 0.1)
				(type default)
			)
			(layer "B.Fab")
		)
		(fp_line
			(start 0.2794 0.9906)
			(end -0.2794 0.9906)
			(stroke
				(width 0.1)
				(type default)
			)
			(layer "B.Fab")
		)
		(fp_line
			(start -0.2794 0.9906)
			(end -0.2794 -0.1016)
			(stroke
				(width 0.1)
				(type default)
			)
			(layer "B.Fab")
		)
		(pad "1" smd rect
			(at 0 0 270)
			(size 0.508 0.508)
			(layers "B.Cu" "B.Mask" "B.Paste")
			(net "A_PG_P12V_MAIN")
		)
		(pad "2" smd rect
			(at 0 0.889 270)
			(size 0.508 0.508)
			(layers "B.Cu" "B.Mask" "B.Paste")
			(net "GND")
		)
		(zone
			(layer "B.Cu")
			(hatch none 0.5)
			(connect_pads
				(clearance 0)
			)
			(min_thickness 0.25)
			(keepout
				(tracks allowed)
				(vias not_allowed)
				(pads allowed)
				(copperpour not_allowed)
				(footprints allowed)
			)
			(placement
				(enabled no)
				(sheetname "")
			)
			(fill
				(thermal_gap 0.5)
				(thermal_bridge_width 0.5)
				(island_removal_mode 0)
			)
			(polygon
				(pts
					(xy 408.1653 -9.017) (xy 408.1653 -8.509) (xy 408.5463 -8.509) (xy 408.5463 -9.017)
				)
			)
		)
		(zone
			(layer "B.Cu")
			(hatch none 0.5)
			(connect_pads
				(clearance 0)
			)
			(min_thickness 0.25)
			(keepout
				(tracks not_allowed)
				(vias allowed)
				(pads allowed)
				(copperpour not_allowed)
				(footprints allowed)
			)
			(placement
				(enabled no)
				(sheetname "")
			)
			(fill
				(thermal_gap 0.5)
				(thermal_bridge_width 0.5)
				(island_removal_mode 0)
			)
			(polygon
				(pts
					(xy 408.5463 -9.017) (xy 408.5463 -8.509) (xy 408.1653 -8.509) (xy 408.1653 -9.017)
				)
			)
		)
	)
	(footprint ""
		(layer "B.Cu")
		(at 411.861 -146.431 -90)
		(property "Reference" "C2L26"
			(at 0 0 90)
			(layer "B.SilkS")
			(hide yes)
			(effects
				(font
					(size 1.27 1.27)
				)
				(justify mirror)
			)
		)
		(property "Value" ""
			(at 0 0 90)
			(layer "B.Fab")
			(effects
				(font
					(size 1.27 1.27)
				)
				(justify mirror)
			)
		)
		(duplicate_pad_numbers_are_jumpers no)
		(fp_poly
			(pts
				(xy -0.3048 -0.1016) (xy -0.3048 0.9906) (xy 0.3048 0.9906) (xy 0.3048 -0.1016)
			)
			(stroke
				(width 0)
				(type default)
			)
			(fill no)
			(layer "B.CrtYd")
		)
		(fp_line
			(start -0.3048 0.9906)
			(end -0.3048 -0.1016)
			(stroke
				(width 0.1)
				(type default)
			)
			(layer "B.Fab")
		)
		(fp_line
			(start 0.3048 0.9906)
			(end -0.3048 0.9906)
			(stroke
				(width 0.1)
				(type default)
			)
			(layer "B.Fab")
		)
		(fp_line
			(start -0.3048 -0.1016)
			(end 0.3048 -0.1016)
			(stroke
				(width 0.1)
				(type default)
			)
			(layer "B.Fab")
		)
		(fp_line
			(start 0.3048 -0.1016)
			(end 0.3048 0.9906)
			(stroke
				(width 0.1)
				(type default)
			)
			(layer "B.Fab")
		)
		(pad "1" smd rect
			(at 0 0 90)
			(size 0.508 0.508)
			(layers "B.Cu" "B.Mask" "B.Paste")
			(net "SATA6G_P5_TX_C_DN")
		)
		(pad "2" smd rect
			(at 0 0.889 90)
			(size 0.508 0.508)
			(layers "B.Cu" "B.Mask" "B.Paste")
			(net "SATA6G_PCH_PCIE_UP_SATA_TXN<5>")
		)
		(zone
			(layer "B.Cu")
			(hatch none 0.5)
			(connect_pads
				(clearance 0)
			)
			(min_thickness 0.25)
			(keepout
				(tracks not_allowed)
				(vias allowed)
				(pads allowed)
				(copperpour not_allowed)
				(footprints allowed)
			)
			(placement
				(enabled no)
				(sheetname "")
			)
			(fill
				(thermal_gap 0.5)
				(thermal_bridge_width 0.5)
				(island_removal_mode 0)
			)
			(polygon
				(pts
					(xy 411.226 -146.177) (xy 411.226 -146.685) (xy 411.607 -146.685) (xy 411.607 -146.177)
				)
			)
		)
		(zone
			(layer "B.Cu")
			(hatch none 0.5)
			(connect_pads
				(clearance 0)
			)
			(min_thickness 0.25)
			(keepout
				(tracks allowed)
				(vias not_allowed)
				(pads allowed)
				(copperpour not_allowed)
				(footprints allowed)
			)
			(placement
				(enabled no)
				(sheetname "")
			)
			(fill
				(thermal_gap 0.5)
				(thermal_bridge_width 0.5)
				(island_removal_mode 0)
			)
			(polygon
				(pts
					(xy 411.607 -146.177) (xy 411.607 -146.685) (xy 411.226 -146.685) (xy 411.226 -146.177)
				)
			)
		)
	)
	(footprint ""
		(layer "B.Cu")
		(at 197.848728 -81.191862 90)
		(property "Reference" "C6P15"
			(at 0 0 90)
			(layer "B.SilkS")
			(hide yes)
			(effects
				(font
					(size 1.27 1.27)
				)
				(justify mirror)
			)
		)
		(property "Value" ""
			(at 0 0 90)
			(layer "B.Fab")
			(effects
				(font
					(size 1.27 1.27)
				)
				(justify mirror)
			)
		)
		(duplicate_pad_numbers_are_jumpers no)
		(fp_rect
			(start -0.7239 -0.2159)
			(end 0.7239 1.9939)
			(stroke
				(width 0)
				(type default)
			)
			(fill no)
			(layer "B.CrtYd")
		)
		(fp_line
			(start 0.7239 -0.2159)
			(end 0.7239 1.9939)
			(stroke
				(width 0.1)
				(type default)
			)
			(layer "B.Fab")
		)
		(fp_line
			(start -0.7239 -0.2159)
			(end 0.7239 -0.2159)
			(stroke
				(width 0.1)
				(type default)
			)
			(layer "B.Fab")
		)
		(fp_line
			(start 0.7239 1.9939)
			(end -0.7239 1.9939)
			(stroke
				(width 0.1)
				(type default)
			)
			(layer "B.Fab")
		)
		(fp_line
			(start -0.7239 1.9939)
			(end -0.7239 -0.2159)
			(stroke
				(width 0.1)
				(type default)
			)
			(layer "B.Fab")
		)
		(pad "1" smd rect
			(at 0 0 270)
			(size 1.27 1.016)
			(layers "B.Cu" "B.Mask" "B.Paste")
			(net "VR_FET_SW_P12V_STBY_PVCCIN_CPU0")
		)
		(pad "2" smd rect
			(at 0 1.778 270)
			(size 1.27 1.016)
			(layers "B.Cu" "B.Mask" "B.Paste")
			(net "GND")
		)
		(zone
			(layer "B.Cu")
			(hatch none 0.5)
			(connect_pads
				(clearance 0)
			)
			(min_thickness 0.25)
			(keepout
				(tracks not_allowed)
				(vias allowed)
				(pads allowed)
				(copperpour not_allowed)
				(footprints allowed)
			)
			(placement
				(enabled no)
				(sheetname "")
			)
			(fill
				(thermal_gap 0.5)
				(thermal_bridge_width 0.5)
				(island_removal_mode 0)
			)
			(polygon
				(pts
					(xy 198.356728 -80.556862) (xy 199.118728 -80.556862) (xy 199.118728 -81.826862) (xy 198.356728 -81.826862)
				)
			)
		)
	)
	(footprint ""
		(layer "B.Cu")
		(at 452.278242 -29.786326)
		(property "Reference" "C8D1"
			(at 0 0 0)
			(layer "B.SilkS")
			(hide yes)
			(effects
				(font
					(size 1.27 1.27)
				)
				(justify mirror)
			)
		)
		(property "Value" ""
			(at 0 0 0)
			(layer "B.Fab")
			(effects
				(font
					(size 1.27 1.27)
				)
				(justify mirror)
			)
		)
		(duplicate_pad_numbers_are_jumpers no)
		(fp_poly
			(pts
				(xy -0.3048 -0.1016) (xy -0.3048 0.9906) (xy 0.3048 0.9906) (xy 0.3048 -0.1016)
			)
			(stroke
				(width 0)
				(type default)
			)
			(fill no)
			(layer "B.CrtYd")
		)
		(fp_line
			(start -0.3048 -0.1016)
			(end 0.3048 -0.1016)
			(stroke
				(width 0.1)
				(type default)
			)
			(layer "B.Fab")
		)
		(fp_line
			(start -0.3048 0.9906)
			(end -0.3048 -0.1016)
			(stroke
				(width 0.1)
				(type default)
			)
			(layer "B.Fab")
		)
		(fp_line
			(start 0.3048 -0.1016)
			(end 0.3048 0.9906)
			(stroke
				(width 0.1)
				(type default)
			)
			(layer "B.Fab")
		)
		(fp_line
			(start 0.3048 0.9906)
			(end -0.3048 0.9906)
			(stroke
				(width 0.1)
				(type default)
			)
			(layer "B.Fab")
		)
		(pad "1" smd rect
			(at 0 0 180)
			(size 0.508 0.508)
			(layers "B.Cu" "B.Mask" "B.Paste")
			(net "P3V3_STBY")
		)
		(pad "2" smd rect
			(at 0 0.889 180)
			(size 0.508 0.508)
			(layers "B.Cu" "B.Mask" "B.Paste")
			(net "GND")
		)
		(zone
			(layer "B.Cu")
			(hatch none 0.5)
			(connect_pads
				(clearance 0)
			)
			(min_thickness 0.25)
			(keepout
				(tracks allowed)
				(vias not_allowed)
				(pads allowed)
				(copperpour not_allowed)
				(footprints allowed)
			)
			(placement
				(enabled no)
				(sheetname "")
			)
			(fill
				(thermal_gap 0.5)
				(thermal_bridge_width 0.5)
				(island_removal_mode 0)
			)
			(polygon
				(pts
					(xy 452.532242 -29.532326) (xy 452.024242 -29.532326) (xy 452.024242 -29.151326) (xy 452.532242 -29.151326)
				)
			)
		)
		(zone
			(layer "B.Cu")
			(hatch none 0.5)
			(connect_pads
				(clearance 0)
			)
			(min_thickness 0.25)
			(keepout
				(tracks not_allowed)
				(vias allowed)
				(pads allowed)
				(copperpour not_allowed)
				(footprints allowed)
			)
			(placement
				(enabled no)
				(sheetname "")
			)
			(fill
				(thermal_gap 0.5)
				(thermal_bridge_width 0.5)
				(island_removal_mode 0)
			)
			(polygon
				(pts
					(xy 452.532242 -29.151326) (xy 452.024242 -29.151326) (xy 452.024242 -29.532326) (xy 452.532242 -29.532326)
				)
			)
		)
	)
)
